(kicad_pcb
	(version 20260206)
	(generator "pcbnew")
	(generator_version "10.0")
	(general
		(thickness 1.6)
		(legacy_teardrops no)
	)
	(paper "A4")
	(title_block
		(title "03242023_DA0F0TMBIJ0_F0T_Motherboard_J_brd_V01_OCP.brd")
		(comment 1 "Grand Teton / footprint 1392 of 6105 (J110), pads 1-48 of 48")
	)
	(layers
		(0 "F.Cu" signal "TOP")
		(4 "In1.Cu" signal "GND")
		(6 "In2.Cu" signal "IN1")
		(8 "In3.Cu" signal "GND1")
		(10 "In4.Cu" signal "IN2")
		(12 "In5.Cu" signal "GND2")
		(14 "In6.Cu" signal "IN3")
		(16 "In7.Cu" signal "GND3")
		(18 "In8.Cu" signal "VCC")
		(20 "In9.Cu" signal "VCC1")
		(22 "In10.Cu" signal "GND4")
		(24 "In11.Cu" signal "IN4")
		(26 "In12.Cu" signal "GND5")
		(28 "In13.Cu" signal "IN5")
		(30 "In14.Cu" signal "GND6")
		(32 "In15.Cu" signal "IN6")
		(34 "In16.Cu" signal "GND7")
		(2 "B.Cu" signal "BOTTOM")
		(9 "F.Adhes" user "F.Adhesive")
		(11 "B.Adhes" user "B.Adhesive")
		(13 "F.Paste" user "Package Geometry/Pastemask Top")
		(15 "B.Paste" user "Package Geometry/Pastemask Bottom")
		(5 "F.SilkS" user "Ref Des/Silkscreen Top")
		(7 "B.SilkS" user "Ref Des/Silkscreen Bottom")
		(1 "F.Mask" user "Board Geometry/Soldermask Top")
		(3 "B.Mask" user "Board Geometry/Soldermask Bottom")
		(17 "Dwgs.User" user "User.Drawings")
		(19 "Cmts.User" user "User.Comments")
		(21 "Eco1.User" user "User.Eco1")
		(23 "Eco2.User" user "User.Eco2")
		(25 "Edge.Cuts" user "Board Geometry/Outline")
		(27 "Margin" user)
		(31 "F.CrtYd" user "Package Geometry/Place Bound Top")
		(29 "B.CrtYd" user "Package Geometry/Place Bound Bottom")
		(35 "F.Fab" user "Ref Des/Assembly Top")
		(33 "B.Fab" user "Ref Des/Assembly Bottom")
	)
	(footprint ""
		(layer "F.Cu")
		(at 125.750066 -440.489848)
		(property "Reference" "J110"
			(at -3.723386 20.59559 0)
			(unlocked yes)
			(layer "F.SilkS")
			(effects
				(font
					(size 0.7874 0.5842)
					(thickness 0.1524)
				)
				(justify left)
			)
		)
		(property "Value" ""
			(at 0 0 0)
			(layer "F.Fab")
			(effects
				(font
					(size 1.27 1.27)
				)
			)
		)
		(duplicate_pad_numbers_are_jumpers no)
		(pad "A1" thru_hole rect
			(at 0 0 180)
			(size 0.766318 0.766318)
			(drill 0.359918)
			(layers "*.Cu" "*.Mask")
			(remove_unused_layers no)
			(net "GPU_FPGA_EROT_RECOV_BUF_N")
			(clearance 0.0508)
			(thermal_gap 0.0508)
			(padstack
				(mode front_inner_back)
				(layer "Inner"
					(shape circle)
					(size 0.766318 0.766318)
					(clearance 0.0508)
				)
				(layer "B.Cu"
					(shape rect)
					(size 0.766318 0.766318)
					(clearance 0.0508)
				)
			)
		)
		(pad "A2" thru_hole circle
			(at 1.999996 0.199898 180)
			(size 0.906272 0.906272)
			(drill 0.499872)
			(layers "*.Cu" "*.Mask")
			(remove_unused_layers no)
			(net "GND")
			(clearance 0.0508)
			(thermal_gap 0.0508)
		)
		(pad "A3" thru_hole circle
			(at 3.999992 0 180)
			(size 0.766318 0.766318)
			(drill 0.359918)
			(layers "*.Cu" "*.Mask")
			(remove_unused_layers no)
			(net "GPU_HMC_PRSNT_N")
			(clearance 0.0508)
			(thermal_gap 0.0508)
		)
		(pad "A4" thru_hole circle
			(at 5.999988 0.199898 180)
			(size 0.906272 0.906272)
			(drill 0.499872)
			(layers "*.Cu" "*.Mask")
			(remove_unused_layers no)
			(net "GND")
			(clearance 0.0508)
			(thermal_gap 0.0508)
		)
		(pad "A5" thru_hole circle
			(at 7.999984 0 180)
			(size 0.766318 0.766318)
			(drill 0.359918)
			(layers "*.Cu" "*.Mask")
			(remove_unused_layers no)
			(net "GPU_BASE_HMC_READY")
			(clearance 0.0508)
			(thermal_gap 0.0508)
		)
		(pad "A6" thru_hole circle
			(at 9.99998 0.199898 180)
			(size 0.906272 0.906272)
			(drill 0.499872)
			(layers "*.Cu" "*.Mask")
			(remove_unused_layers no)
			(net "GND")
			(clearance 0.0508)
			(thermal_gap 0.0508)
		)
		(pad "A7" thru_hole circle
			(at 11.999976 0 180)
			(size 0.766318 0.766318)
			(drill 0.359918)
			(layers "*.Cu" "*.Mask")
			(remove_unused_layers no)
			(net "GPU_BASE_STBY_EN_BUF")
			(clearance 0.0508)
			(thermal_gap 0.0508)
		)
		(pad "A8" thru_hole circle
			(at 13.999972 0.199898 180)
			(size 0.906272 0.906272)
			(drill 0.499872)
			(layers "*.Cu" "*.Mask")
			(remove_unused_layers no)
			(net "GND")
			(clearance 0.0508)
			(thermal_gap 0.0508)
		)
		(pad "B1" thru_hole circle
			(at 0 1.199896 180)
			(size 0.906272 0.906272)
			(drill 0.499872)
			(layers "*.Cu" "*.Mask")
			(remove_unused_layers no)
			(net "GND")
			(clearance 0.0508)
			(thermal_gap 0.0508)
		)
		(pad "B3" thru_hole circle
			(at 3.999992 1.199896 180)
			(size 0.906272 0.906272)
			(drill 0.499872)
			(layers "*.Cu" "*.Mask")
			(remove_unused_layers no)
			(net "GND")
			(clearance 0.0508)
			(thermal_gap 0.0508)
		)
		(pad "B5" thru_hole circle
			(at 7.999984 1.199896 180)
			(size 0.906272 0.906272)
			(drill 0.499872)
			(layers "*.Cu" "*.Mask")
			(remove_unused_layers no)
			(net "GND")
			(clearance 0.0508)
			(thermal_gap 0.0508)
		)
		(pad "B7" thru_hole circle
			(at 11.999976 1.199896 180)
			(size 0.906272 0.906272)
			(drill 0.499872)
			(layers "*.Cu" "*.Mask")
			(remove_unused_layers no)
			(net "GND")
			(clearance 0.0508)
			(thermal_gap 0.0508)
		)
		(pad "D2" thru_hole circle
			(at 1.999996 3.800094 180)
			(size 0.906272 0.906272)
			(drill 0.499872)
			(layers "*.Cu" "*.Mask")
			(remove_unused_layers no)
			(net "GND")
			(clearance 0.0508)
			(thermal_gap 0.0508)
		)
		(pad "D4" thru_hole circle
			(at 5.999988 3.800094 180)
			(size 0.906272 0.906272)
			(drill 0.499872)
			(layers "*.Cu" "*.Mask")
			(remove_unused_layers no)
			(net "GND")
			(clearance 0.0508)
			(thermal_gap 0.0508)
		)
		(pad "D6" thru_hole circle
			(at 9.99998 3.800094 180)
			(size 0.906272 0.906272)
			(drill 0.499872)
			(layers "*.Cu" "*.Mask")
			(remove_unused_layers no)
			(net "GND")
			(clearance 0.0508)
			(thermal_gap 0.0508)
		)
		(pad "D8" thru_hole circle
			(at 13.999972 3.800094 180)
			(size 0.906272 0.906272)
			(drill 0.499872)
			(layers "*.Cu" "*.Mask")
			(remove_unused_layers no)
			(net "GND")
			(clearance 0.0508)
			(thermal_gap 0.0508)
		)
		(pad "E1" thru_hole circle
			(at 0 4.800092 180)
			(size 0.906272 0.906272)
			(drill 0.499872)
			(layers "*.Cu" "*.Mask")
			(remove_unused_layers no)
			(net "GND")
			(clearance 0.0508)
			(thermal_gap 0.0508)
		)
		(pad "E3" thru_hole circle
			(at 3.999992 4.800092 180)
			(size 0.906272 0.906272)
			(drill 0.499872)
			(layers "*.Cu" "*.Mask")
			(remove_unused_layers no)
			(net "GND")
			(clearance 0.0508)
			(thermal_gap 0.0508)
		)
		(pad "E5" thru_hole circle
			(at 7.999984 4.800092 180)
			(size 0.906272 0.906272)
			(drill 0.499872)
			(layers "*.Cu" "*.Mask")
			(remove_unused_layers no)
			(net "GND")
			(clearance 0.0508)
			(thermal_gap 0.0508)
		)
		(pad "E7" thru_hole circle
			(at 11.999976 4.800092 180)
			(size 0.906272 0.906272)
			(drill 0.499872)
			(layers "*.Cu" "*.Mask")
			(remove_unused_layers no)
			(net "GND")
			(clearance 0.0508)
			(thermal_gap 0.0508)
		)
		(pad "G2" thru_hole circle
			(at 1.999996 7.400036 180)
			(size 0.906272 0.906272)
			(drill 0.499872)
			(layers "*.Cu" "*.Mask")
			(remove_unused_layers no)
			(net "GND")
			(clearance 0.0508)
			(thermal_gap 0.0508)
		)
		(pad "G4" thru_hole circle
			(at 5.999988 7.400036 180)
			(size 0.906272 0.906272)
			(drill 0.499872)
			(layers "*.Cu" "*.Mask")
			(remove_unused_layers no)
			(net "GND")
			(clearance 0.0508)
			(thermal_gap 0.0508)
		)
		(pad "G6" thru_hole circle
			(at 9.99998 7.400036 180)
			(size 0.906272 0.906272)
			(drill 0.499872)
			(layers "*.Cu" "*.Mask")
			(remove_unused_layers no)
			(net "GND")
			(clearance 0.0508)
			(thermal_gap 0.0508)
		)
		(pad "G8" thru_hole circle
			(at 13.999972 7.400036 180)
			(size 0.906272 0.906272)
			(drill 0.499872)
			(layers "*.Cu" "*.Mask")
			(remove_unused_layers no)
			(net "GND")
			(clearance 0.0508)
			(thermal_gap 0.0508)
		)
		(pad "H1" thru_hole circle
			(at 0 8.400034 180)
			(size 0.906272 0.906272)
			(drill 0.499872)
			(layers "*.Cu" "*.Mask")
			(remove_unused_layers no)
			(net "GND")
			(clearance 0.0508)
			(thermal_gap 0.0508)
		)
		(pad "H3" thru_hole circle
			(at 3.999992 8.400034 180)
			(size 0.906272 0.906272)
			(drill 0.499872)
			(layers "*.Cu" "*.Mask")
			(remove_unused_layers no)
			(net "GND")
			(clearance 0.0508)
			(thermal_gap 0.0508)
		)
		(pad "H5" thru_hole circle
			(at 7.999984 8.400034 180)
			(size 0.906272 0.906272)
			(drill 0.499872)
			(layers "*.Cu" "*.Mask")
			(remove_unused_layers no)
			(net "GND")
			(clearance 0.0508)
			(thermal_gap 0.0508)
		)
		(pad "H7" thru_hole circle
			(at 11.999976 8.400034 180)
			(size 0.906272 0.906272)
			(drill 0.499872)
			(layers "*.Cu" "*.Mask")
			(remove_unused_layers no)
			(net "GND")
			(clearance 0.0508)
			(thermal_gap 0.0508)
		)
		(pad "J2" thru_hole circle
			(at 1.999996 10.999978 180)
			(size 0.906272 0.906272)
			(drill 0.499872)
			(layers "*.Cu" "*.Mask")
			(remove_unused_layers no)
			(net "GND")
			(clearance 0.0508)
			(thermal_gap 0.0508)
		)
		(pad "J4" thru_hole circle
			(at 5.999988 10.999978 180)
			(size 0.906272 0.906272)
			(drill 0.499872)
			(layers "*.Cu" "*.Mask")
			(remove_unused_layers no)
			(net "GND")
			(clearance 0.0508)
			(thermal_gap 0.0508)
		)
		(pad "J6" thru_hole circle
			(at 9.99998 10.999978 180)
			(size 0.906272 0.906272)
			(drill 0.499872)
			(layers "*.Cu" "*.Mask")
			(remove_unused_layers no)
			(net "GND")
			(clearance 0.0508)
			(thermal_gap 0.0508)
		)
		(pad "J8" thru_hole circle
			(at 13.999972 10.999978 180)
			(size 0.906272 0.906272)
			(drill 0.499872)
			(layers "*.Cu" "*.Mask")
			(remove_unused_layers no)
			(net "GND")
			(clearance 0.0508)
			(thermal_gap 0.0508)
		)
		(pad "K1" thru_hole circle
			(at 0 11.999976 180)
			(size 0.906272 0.906272)
			(drill 0.499872)
			(layers "*.Cu" "*.Mask")
			(remove_unused_layers no)
			(net "GND")
			(clearance 0.0508)
			(thermal_gap 0.0508)
		)
		(pad "K3" thru_hole circle
			(at 3.999992 11.999976 180)
			(size 0.906272 0.906272)
			(drill 0.499872)
			(layers "*.Cu" "*.Mask")
			(remove_unused_layers no)
			(net "GND")
			(clearance 0.0508)
			(thermal_gap 0.0508)
		)
		(pad "K5" thru_hole circle
			(at 7.999984 11.999976 180)
			(size 0.906272 0.906272)
			(drill 0.499872)
			(layers "*.Cu" "*.Mask")
			(remove_unused_layers no)
			(net "GND")
			(clearance 0.0508)
			(thermal_gap 0.0508)
		)
		(pad "K7" thru_hole circle
			(at 11.999976 11.999976 180)
			(size 0.906272 0.906272)
			(drill 0.499872)
			(layers "*.Cu" "*.Mask")
			(remove_unused_layers no)
			(net "GND")
			(clearance 0.0508)
			(thermal_gap 0.0508)
		)
		(pad "M2" thru_hole circle
			(at 1.999996 14.59992 180)
			(size 0.906272 0.906272)
			(drill 0.499872)
			(layers "*.Cu" "*.Mask")
			(remove_unused_layers no)
			(net "GND")
			(clearance 0.0508)
			(thermal_gap 0.0508)
		)
		(pad "M4" thru_hole circle
			(at 5.999988 14.59992 180)
			(size 0.906272 0.906272)
			(drill 0.499872)
			(layers "*.Cu" "*.Mask")
			(remove_unused_layers no)
			(net "GND")
			(clearance 0.0508)
			(thermal_gap 0.0508)
		)
		(pad "M6" thru_hole circle
			(at 9.99998 14.59992 180)
			(size 0.906272 0.906272)
			(drill 0.499872)
			(layers "*.Cu" "*.Mask")
			(remove_unused_layers no)
			(net "GND")
			(clearance 0.0508)
			(thermal_gap 0.0508)
		)
		(pad "M8" thru_hole circle
			(at 13.999972 14.59992 180)
			(size 0.906272 0.906272)
			(drill 0.499872)
			(layers "*.Cu" "*.Mask")
			(remove_unused_layers no)
			(net "GND")
			(clearance 0.0508)
			(thermal_gap 0.0508)
		)
		(pad "N1" thru_hole circle
			(at 0 15.599918 180)
			(size 0.906272 0.906272)
			(drill 0.499872)
			(layers "*.Cu" "*.Mask")
			(remove_unused_layers no)
			(net "GND")
			(clearance 0.0508)
			(thermal_gap 0.0508)
		)
		(pad "N2" thru_hole circle
			(at 1.999996 15.80007 180)
			(size 0.766318 0.766318)
			(drill 0.359918)
			(layers "*.Cu" "*.Mask")
			(remove_unused_layers no)
			(net "GPU_FPGA_BOOT_EN_BUF")
			(clearance 0.0508)
			(thermal_gap 0.0508)
		)
		(pad "N3" thru_hole circle
			(at 3.999992 15.599918 180)
			(size 0.906272 0.906272)
			(drill 0.499872)
			(layers "*.Cu" "*.Mask")
			(remove_unused_layers no)
			(net "GND")
			(clearance 0.0508)
			(thermal_gap 0.0508)
		)
		(pad "N4" thru_hole circle
			(at 5.999988 15.80007 180)
			(size 0.766318 0.766318)
			(drill 0.359918)
			(layers "*.Cu" "*.Mask")
			(remove_unused_layers no)
			(net "FM_SMB_1_ALERT_GPU_N")
			(clearance 0.0508)
			(thermal_gap 0.0508)
		)
		(pad "N5" thru_hole circle
			(at 7.999984 15.599918 180)
			(size 0.906272 0.906272)
			(drill 0.499872)
			(layers "*.Cu" "*.Mask")
			(remove_unused_layers no)
			(net "GND")
			(clearance 0.0508)
			(thermal_gap 0.0508)
		)
		(pad "N6" thru_hole circle
			(at 9.99998 15.80007 180)
			(size 0.766318 0.766318)
			(drill 0.359918)
			(layers "*.Cu" "*.Mask")
			(remove_unused_layers no)
			(net "FM_SMB_2_ALERT_GPU_N")
			(clearance 0.0508)
			(thermal_gap 0.0508)
		)
		(pad "N7" thru_hole circle
			(at 11.999976 15.599918 180)
			(size 0.906272 0.906272)
			(drill 0.499872)
			(layers "*.Cu" "*.Mask")
			(remove_unused_layers no)
			(net "GND")
			(clearance 0.0508)
			(thermal_gap 0.0508)
		)
		(pad "N8" thru_hole circle
			(at 13.999972 15.80007 180)
			(size 0.766318 0.766318)
			(drill 0.359918)
			(layers "*.Cu" "*.Mask")
			(remove_unused_layers no)
			(net "GPU_FPGA_EROT_RST_BUF_N")
			(clearance 0.0508)
			(thermal_gap 0.0508)
		)
	)
)
